# T6G (Grand Teton) — schematic netlist excerpt (pin names and nets, part order shuffled) for the footprints in the layout excerpt that follows; sources: Cadence DE-HDL packaged netlist, KiCad conversion of 04192023_DAF0TMB3IC0_F0TG_MB_C_brd_V02_OCP.brd

R3668  Q_RES  1K 1% CHIP  pkg 0402LF  page 257 : A = ADC128_A1 ; B = GND
C6710  Q_CAP_DIFFBUS  DIFF BUS_0.22UF 6.3V 20% X6S  pkg C0201  page 341 : \1\ = P5E_CPU1_P2_TX_BUF_C_DN<8> ; \2\ = P5E_CPU1_P2_TX_BUF_DN<8>
PR464  Q_RES  13.7K 1% CHIP  pkg 0402LF  page 224 : A = GND ; B = PVDD11_S3_P1_ADDR_CFG

(kicad_pcb
	(version 20260206)
	(generator "pcbnew")
	(generator_version "10.0")
	(general
		(thickness 1.6)
		(legacy_teardrops no)
	)
	(paper "A4")
	(title_block
		(title "04192023_DAF0TMB3IC0_F0TG_MB_C_brd_V02_OCP.brd")
		(comment 1 "Grand Teton / footprints 1522-1524 of 8354")
	)
	(layers
		(0 "F.Cu" signal "TOP")
		(4 "In1.Cu" signal "GND")
		(6 "In2.Cu" signal "IN1")
		(8 "In3.Cu" signal "GND1")
		(10 "In4.Cu" signal "IN2")
		(12 "In5.Cu" signal "GND2")
		(14 "In6.Cu" signal "IN3")
		(16 "In7.Cu" signal "GND3")
		(18 "In8.Cu" signal "VCC")
		(20 "In9.Cu" signal "VCC1")
		(22 "In10.Cu" signal "GND4")
		(24 "In11.Cu" signal "IN4")
		(26 "In12.Cu" signal "GND5")
		(28 "In13.Cu" signal "IN5")
		(30 "In14.Cu" signal "GND6")
		(32 "In15.Cu" signal "IN6")
		(34 "In16.Cu" signal "GND7")
		(2 "B.Cu" signal "BOTTOM")
		(9 "F.Adhes" user "F.Adhesive")
		(11 "B.Adhes" user "B.Adhesive")
		(13 "F.Paste" user "Package Geometry/Pastemask Top")
		(15 "B.Paste" user "Package Geometry/Pastemask Bottom")
		(5 "F.SilkS" user "Ref Des/Silkscreen Top")
		(7 "B.SilkS" user "Ref Des/Silkscreen Bottom")
		(1 "F.Mask" user "Board Geometry/Soldermask Top")
		(3 "B.Mask" user "Board Geometry/Soldermask Bottom")
		(17 "Dwgs.User" user "User.Drawings")
		(19 "Cmts.User" user "User.Comments")
		(21 "Eco1.User" user "User.Eco1")
		(23 "Eco2.User" user "User.Eco2")
		(25 "Edge.Cuts" user "Board Geometry/Outline")
		(27 "Margin" user)
		(31 "F.CrtYd" user "Package Geometry/Place Bound Top")
		(29 "B.CrtYd" user "Package Geometry/Place Bound Bottom")
		(35 "F.Fab" user "Ref Des/Assembly Top")
		(33 "B.Fab" user "Ref Des/Assembly Bottom")
	)
	(footprint ""
		(layer "F.Cu")
		(at 166.942516 -347.289882 180)
		(property "Reference" "PR464"
			(at 0 0 180)
			(layer "F.SilkS")
			(hide yes)
			(effects
				(font
					(size 1.27 1.27)
				)
			)
		)
		(property "Value" ""
			(at 0 0 180)
			(layer "F.Fab")
			(effects
				(font
					(size 1.27 1.27)
				)
			)
		)
		(duplicate_pad_numbers_are_jumpers no)
		(fp_line
			(start 0.7874 0.4064)
			(end -0.7874 0.4064)
			(stroke
				(width 0.1524)
				(type default)
			)
			(layer "F.SilkS")
		)
		(fp_line
			(start 0.7874 -0.4064)
			(end 0.7874 0.4064)
			(stroke
				(width 0.1524)
				(type default)
			)
			(layer "F.SilkS")
		)
		(fp_line
			(start -0.7874 0.4064)
			(end -0.7874 -0.4064)
			(stroke
				(width 0.1524)
				(type default)
			)
			(layer "F.SilkS")
		)
		(fp_line
			(start -0.7874 -0.4064)
			(end 0.7874 -0.4064)
			(stroke
				(width 0.1524)
				(type default)
			)
			(layer "F.SilkS")
		)
		(fp_line
			(start 0.67945 0.3048)
			(end 0.120396 0.3048)
			(stroke
				(width 0.1)
				(type default)
			)
			(layer "F.Fab")
		)
		(fp_line
			(start 0.67945 -0.3048)
			(end 0.67945 0.3048)
			(stroke
				(width 0.1)
				(type default)
			)
			(layer "F.Fab")
		)
		(fp_line
			(start 0.12065 -0.2794)
			(end 0.12065 -0.3048)
			(stroke
				(width 0.1)
				(type default)
			)
			(layer "F.Fab")
		)
		(fp_line
			(start 0.12065 -0.3048)
			(end 0.67945 -0.3048)
			(stroke
				(width 0.1)
				(type default)
			)
			(layer "F.Fab")
		)
		(fp_line
			(start 0.120396 0.3048)
			(end 0.120396 0.2794)
			(stroke
				(width 0.1)
				(type default)
			)
			(layer "F.Fab")
		)
		(fp_line
			(start 0.120396 0.2794)
			(end -0.12065 0.2794)
			(stroke
				(width 0.1)
				(type default)
			)
			(layer "F.Fab")
		)
		(fp_line
			(start -0.12065 0.3048)
			(end -0.67945 0.3048)
			(stroke
				(width 0.1)
				(type default)
			)
			(layer "F.Fab")
		)
		(fp_line
			(start -0.12065 0.2794)
			(end -0.12065 0.3048)
			(stroke
				(width 0.1)
				(type default)
			)
			(layer "F.Fab")
		)
		(fp_line
			(start -0.12065 -0.2794)
			(end 0.12065 -0.2794)
			(stroke
				(width 0.1)
				(type default)
			)
			(layer "F.Fab")
		)
		(fp_line
			(start -0.12065 -0.305054)
			(end -0.12065 -0.2794)
			(stroke
				(width 0.1)
				(type default)
			)
			(layer "F.Fab")
		)
		(fp_line
			(start -0.67945 0.3048)
			(end -0.67945 -0.305054)
			(stroke
				(width 0.1)
				(type default)
			)
			(layer "F.Fab")
		)
		(fp_line
			(start -0.67945 -0.305054)
			(end -0.12065 -0.305054)
			(stroke
				(width 0.1)
				(type default)
			)
			(layer "F.Fab")
		)
		(pad "1" smd circle
			(at -0.40005 0 180)
			(size 0 0)
			(layers "F.Cu" "F.Mask" "F.Paste")
			(net "GND")
		)
		(pad "2" smd circle
			(at 0.40005 0 180)
			(size 0 0)
			(layers "F.Cu" "F.Mask" "F.Paste")
			(net "PVDD11_S3_P1_ADDR_CFG")
		)
	)
	(footprint ""
		(layer "F.Cu")
		(at 305.819048 -40.890698 180)
		(property "Reference" "R3668"
			(at 0 0 180)
			(layer "F.SilkS")
			(hide yes)
			(effects
				(font
					(size 1.27 1.27)
				)
			)
		)
		(property "Value" ""
			(at 0 0 180)
			(layer "F.Fab")
			(effects
				(font
					(size 1.27 1.27)
				)
			)
		)
		(duplicate_pad_numbers_are_jumpers no)
		(fp_line
			(start 0.7874 0.4064)
			(end -0.7874 0.4064)
			(stroke
				(width 0.1524)
				(type default)
			)
			(layer "F.SilkS")
		)
		(fp_line
			(start 0.7874 -0.4064)
			(end 0.7874 0.4064)
			(stroke
				(width 0.1524)
				(type default)
			)
			(layer "F.SilkS")
		)
		(fp_line
			(start -0.7874 0.4064)
			(end -0.7874 -0.4064)
			(stroke
				(width 0.1524)
				(type default)
			)
			(layer "F.SilkS")
		)
		(fp_line
			(start -0.7874 -0.4064)
			(end 0.7874 -0.4064)
			(stroke
				(width 0.1524)
				(type default)
			)
			(layer "F.SilkS")
		)
		(fp_line
			(start 0.67945 0.3048)
			(end 0.120396 0.3048)
			(stroke
				(width 0.1)
				(type default)
			)
			(layer "F.Fab")
		)
		(fp_line
			(start 0.67945 -0.3048)
			(end 0.67945 0.3048)
			(stroke
				(width 0.1)
				(type default)
			)
			(layer "F.Fab")
		)
		(fp_line
			(start 0.12065 -0.2794)
			(end 0.12065 -0.3048)
			(stroke
				(width 0.1)
				(type default)
			)
			(layer "F.Fab")
		)
		(fp_line
			(start 0.12065 -0.3048)
			(end 0.67945 -0.3048)
			(stroke
				(width 0.1)
				(type default)
			)
			(layer "F.Fab")
		)
		(fp_line
			(start 0.120396 0.3048)
			(end 0.120396 0.2794)
			(stroke
				(width 0.1)
				(type default)
			)
			(layer "F.Fab")
		)
		(fp_line
			(start 0.120396 0.2794)
			(end -0.12065 0.2794)
			(stroke
				(width 0.1)
				(type default)
			)
			(layer "F.Fab")
		)
		(fp_line
			(start -0.12065 0.3048)
			(end -0.67945 0.3048)
			(stroke
				(width 0.1)
				(type default)
			)
			(layer "F.Fab")
		)
		(fp_line
			(start -0.12065 0.2794)
			(end -0.12065 0.3048)
			(stroke
				(width 0.1)
				(type default)
			)
			(layer "F.Fab")
		)
		(fp_line
			(start -0.12065 -0.2794)
			(end 0.12065 -0.2794)
			(stroke
				(width 0.1)
				(type default)
			)
			(layer "F.Fab")
		)
		(fp_line
			(start -0.12065 -0.305054)
			(end -0.12065 -0.2794)
			(stroke
				(width 0.1)
				(type default)
			)
			(layer "F.Fab")
		)
		(fp_line
			(start -0.67945 0.3048)
			(end -0.67945 -0.305054)
			(stroke
				(width 0.1)
				(type default)
			)
			(layer "F.Fab")
		)
		(fp_line
			(start -0.67945 -0.305054)
			(end -0.12065 -0.305054)
			(stroke
				(width 0.1)
				(type default)
			)
			(layer "F.Fab")
		)
		(pad "1" smd circle
			(at -0.40005 0 180)
			(size 0 0)
			(layers "F.Cu" "F.Mask" "F.Paste")
			(net "ADC128_A1")
		)
		(pad "2" smd circle
			(at 0.40005 0 180)
			(size 0 0)
			(layers "F.Cu" "F.Mask" "F.Paste")
			(net "GND")
		)
	)
	(footprint ""
		(layer "F.Cu")
		(at 139.374626 -408.517344 -90)
		(property "Reference" "C6710"
			(at 0 0 270)
			(layer "F.SilkS")
			(hide yes)
			(effects
				(font
					(size 1.27 1.27)
				)
			)
		)
		(property "Value" ""
			(at 0 0 270)
			(layer "F.Fab")
			(effects
				(font
					(size 1.27 1.27)
				)
			)
		)
		(duplicate_pad_numbers_are_jumpers no)
		(fp_line
			(start -0.299974 0.150114)
			(end -0.299974 -0.150114)
			(stroke
				(width 0.1)
				(type default)
			)
			(layer "F.Fab")
		)
		(fp_line
			(start 0.299974 0.150114)
			(end -0.299974 0.150114)
			(stroke
				(width 0.1)
				(type default)
			)
			(layer "F.Fab")
		)
		(fp_line
			(start -0.299974 -0.150114)
			(end 0.299974 -0.150114)
			(stroke
				(width 0.1)
				(type default)
			)
			(layer "F.Fab")
		)
		(fp_line
			(start 0.299974 -0.150114)
			(end 0.299974 0.150114)
			(stroke
				(width 0.1)
				(type default)
			)
			(layer "F.Fab")
		)
		(pad "1" smd rect
			(at -0.2667 0 270)
			(size 0.3048 0.381)
			(layers "F.Cu" "F.Mask" "F.Paste")
			(net "P5E_CPU1_P2_TX_BUF_C_DN<8>")
		)
		(pad "2" smd rect
			(at 0.2667 0 270)
			(size 0.3048 0.381)
			(layers "F.Cu" "F.Mask" "F.Paste")
			(net "P5E_CPU1_P2_TX_BUF_DN<8>")
		)
	)
)
